(kicad_pcb
	(version 20260206)
	(generator "pcbnew")
	(generator_version "10.0")
	(general
		(thickness 1.6)
		(legacy_teardrops no)
	)
	(paper "A4")
	(title_block
		(title "04192023_DAF0TMB3IC0_F0TG_MB_C_brd_V02_OCP.brd")
		(comment 1 "Grand Teton / footprint 3955 of 8354 (U25), pads 4669-4783 of 6102")
	)
	(layers
		(0 "F.Cu" signal "TOP")
		(4 "In1.Cu" signal "GND")
		(6 "In2.Cu" signal "IN1")
		(8 "In3.Cu" signal "GND1")
		(10 "In4.Cu" signal "IN2")
		(12 "In5.Cu" signal "GND2")
		(14 "In6.Cu" signal "IN3")
		(16 "In7.Cu" signal "GND3")
		(18 "In8.Cu" signal "VCC")
		(20 "In9.Cu" signal "VCC1")
		(22 "In10.Cu" signal "GND4")
		(24 "In11.Cu" signal "IN4")
		(26 "In12.Cu" signal "GND5")
		(28 "In13.Cu" signal "IN5")
		(30 "In14.Cu" signal "GND6")
		(32 "In15.Cu" signal "IN6")
		(34 "In16.Cu" signal "GND7")
		(2 "B.Cu" signal "BOTTOM")
		(9 "F.Adhes" user "F.Adhesive")
		(11 "B.Adhes" user "B.Adhesive")
		(13 "F.Paste" user "Package Geometry/Pastemask Top")
		(15 "B.Paste" user "Package Geometry/Pastemask Bottom")
		(5 "F.SilkS" user "Ref Des/Silkscreen Top")
		(7 "B.SilkS" user "Ref Des/Silkscreen Bottom")
		(1 "F.Mask" user "Board Geometry/Soldermask Top")
		(3 "B.Mask" user "Board Geometry/Soldermask Bottom")
		(17 "Dwgs.User" user "User.Drawings")
		(19 "Cmts.User" user "User.Comments")
		(21 "Eco1.User" user "User.Eco1")
		(23 "Eco2.User" user "User.Eco2")
		(25 "Edge.Cuts" user "Board Geometry/Outline")
		(27 "Margin" user)
		(31 "F.CrtYd" user "Package Geometry/Place Bound Top")
		(29 "B.CrtYd" user "Package Geometry/Place Bound Bottom")
		(35 "F.Fab" user "Ref Des/Assembly Top")
		(33 "B.Fab" user "Ref Des/Assembly Bottom")
	)
	(footprint ""
		(layer "F.Cu")
		(at 359.867962 -258.880102 180)
		(property "Reference" "U25"
			(at -45.78477 -62.086744 0)
			(unlocked yes)
			(layer "F.SilkS")
			(effects
				(font
					(size 0.7874 0.5842)
					(thickness 0.1524)
				)
			)
		)
		(property "Value" ""
			(at 0 0 180)
			(layer "F.Fab")
			(effects
				(font
					(size 1.27 1.27)
				)
			)
		)
		(duplicate_pad_numbers_are_jumpers no)
		(pad "DE64" smd circle
			(at 23.82012 33.56991 180)
			(size 0.450088 0.450088)
			(layers "F.Cu" "F.Mask" "F.Paste")
			(net "M_B_CPU0_SB_DQ<30>")
		)
		(pad "DE65" smd circle
			(at 24.75992 33.56991 180)
			(size 0.450088 0.450088)
			(layers "F.Cu" "F.Mask" "F.Paste")
			(net "PVDDIO_P0")
		)
		(pad "DE66" smd circle
			(at 25.699974 33.56991 180)
			(size 0.450088 0.450088)
			(layers "F.Cu" "F.Mask" "F.Paste")
			(net "M_F_CPU0_SB_DQ<29>")
		)
		(pad "DE67" smd circle
			(at 26.640028 33.56991 180)
			(size 0.450088 0.450088)
			(layers "F.Cu" "F.Mask" "F.Paste")
			(net "M_F_CPU0_SB_DQ<30>")
		)
		(pad "DE68" smd circle
			(at 27.580082 33.56991 180)
			(size 0.450088 0.450088)
			(layers "F.Cu" "F.Mask" "F.Paste")
			(net "GND")
		)
		(pad "DE69" smd circle
			(at 28.519882 33.56991 180)
			(size 0.450088 0.450088)
			(layers "F.Cu" "F.Mask" "F.Paste")
			(net "M_E_CPU0_SB_DQ<29>")
		)
		(pad "DE70" smd circle
			(at 29.459936 33.56991 180)
			(size 0.450088 0.450088)
			(layers "F.Cu" "F.Mask" "F.Paste")
			(net "GND")
		)
		(pad "DE71" smd circle
			(at 30.39999 33.56991 180)
			(size 0.450088 0.450088)
			(layers "F.Cu" "F.Mask" "F.Paste")
			(net "M_E_CPU0_SB_DQ<30>")
		)
		(pad "DE72" smd circle
			(at 31.340044 33.56991 180)
			(size 0.450088 0.450088)
			(layers "F.Cu" "F.Mask" "F.Paste")
			(net "PVDDIO_P0")
		)
		(pad "DE73" smd circle
			(at 32.280098 33.56991 180)
			(size 0.450088 0.450088)
			(layers "F.Cu" "F.Mask" "F.Paste")
			(net "M_A_CPU0_SB_DQ<29>")
		)
		(pad "DE74" smd circle
			(at 33.219898 33.56991 180)
			(size 0.450088 0.450088)
			(layers "F.Cu" "F.Mask" "F.Paste")
			(net "M_A_CPU0_SB_DQ<30>")
		)
		(pad "DE75" smd circle
			(at 34.159952 33.56991 180)
			(size 0.450088 0.450088)
			(layers "F.Cu" "F.Mask" "F.Paste")
			(net "GND")
		)
		(pad "DF2" smd circle
			(at -33.990026 34.379916 180)
			(size 0.450088 0.450088)
			(layers "F.Cu" "F.Mask" "F.Paste")
			(net "M_G_CPU0_SB_DQ<31>")
		)
		(pad "DF3" smd circle
			(at -33.049972 34.379916 180)
			(size 0.450088 0.450088)
			(layers "F.Cu" "F.Mask" "F.Paste")
			(net "GND")
		)
		(pad "DF4" smd circle
			(at -32.109918 34.379916 180)
			(size 0.450088 0.450088)
			(layers "F.Cu" "F.Mask" "F.Paste")
			(net "GND")
		)
		(pad "DF5" smd circle
			(at -31.170118 34.379916 180)
			(size 0.450088 0.450088)
			(layers "F.Cu" "F.Mask" "F.Paste")
			(net "GND")
		)
		(pad "DF6" smd circle
			(at -30.230064 34.379916 180)
			(size 0.450088 0.450088)
			(layers "F.Cu" "F.Mask" "F.Paste")
			(net "GND")
		)
		(pad "DF7" smd circle
			(at -29.29001 34.379916 180)
			(size 0.450088 0.450088)
			(layers "F.Cu" "F.Mask" "F.Paste")
			(net "M_K_CPU0_SB_DQ<31>")
		)
		(pad "DF8" smd circle
			(at -28.349956 34.379916 180)
			(size 0.450088 0.450088)
			(layers "F.Cu" "F.Mask" "F.Paste")
			(net "GND")
		)
		(pad "DF9" smd circle
			(at -27.409902 34.379916 180)
			(size 0.450088 0.450088)
			(layers "F.Cu" "F.Mask" "F.Paste")
			(net "M_L_CPU0_SB_DQ<31>")
		)
		(pad "DF10" smd circle
			(at -26.470102 34.379916 180)
			(size 0.450088 0.450088)
			(layers "F.Cu" "F.Mask" "F.Paste")
			(net "GND")
		)
		(pad "DF11" smd circle
			(at -25.530048 34.379916 180)
			(size 0.450088 0.450088)
			(layers "F.Cu" "F.Mask" "F.Paste")
			(net "GND")
		)
		(pad "DF12" smd circle
			(at -24.589994 34.379916 180)
			(size 0.450088 0.450088)
			(layers "F.Cu" "F.Mask" "F.Paste")
			(net "GND")
		)
		(pad "DF13" smd circle
			(at -23.64994 34.379916 180)
			(size 0.450088 0.450088)
			(layers "F.Cu" "F.Mask" "F.Paste")
			(net "GND")
		)
		(pad "DF14" smd circle
			(at -22.709886 34.379916 180)
			(size 0.450088 0.450088)
			(layers "F.Cu" "F.Mask" "F.Paste")
			(net "M_H_CPU0_SB_DQ<31>")
		)
		(pad "DF15" smd circle
			(at -21.770086 34.379916 180)
			(size 0.450088 0.450088)
			(layers "F.Cu" "F.Mask" "F.Paste")
			(net "GND")
		)
		(pad "DF16" smd circle
			(at -20.830032 34.379916 180)
			(size 0.450088 0.450088)
			(layers "F.Cu" "F.Mask" "F.Paste")
			(net "M_J_CPU0_SB_DQ<31>")
		)
		(pad "DF17" smd circle
			(at -19.889978 34.379916 180)
			(size 0.450088 0.450088)
			(layers "F.Cu" "F.Mask" "F.Paste")
			(net "GND")
		)
		(pad "DF18" smd circle
			(at -18.949924 34.379916 180)
			(size 0.450088 0.450088)
			(layers "F.Cu" "F.Mask" "F.Paste")
			(net "GND")
		)
		(pad "DF19" smd circle
			(at -18.010124 34.379916 180)
			(size 0.450088 0.450088)
			(layers "F.Cu" "F.Mask" "F.Paste")
			(net "GND")
		)
		(pad "DF20" smd circle
			(at -17.07007 34.379916 180)
			(size 0.450088 0.450088)
			(layers "F.Cu" "F.Mask" "F.Paste")
			(net "GND")
		)
		(pad "DF21" smd circle
			(at -16.130016 34.379916 180)
			(size 0.450088 0.450088)
			(layers "F.Cu" "F.Mask" "F.Paste")
			(net "M_I_CPU0_SB_DQ<31>")
		)
		(pad "DF22" smd circle
			(at -15.189962 34.379916 180)
			(size 0.450088 0.450088)
			(layers "F.Cu" "F.Mask" "F.Paste")
			(net "GND")
		)
		(pad "DF23" smd circle
			(at -14.249908 34.379916 180)
			(size 0.450088 0.450088)
			(layers "F.Cu" "F.Mask" "F.Paste")
			(net "GND")
		)
		(pad "DF24" smd circle
			(at -13.310108 34.379916 180)
			(size 0.450088 0.450088)
			(layers "F.Cu" "F.Mask" "F.Paste")
			(net "ESPI_CPU0_R_ALERT_N")
		)
		(pad "DF25" smd circle
			(at -12.370054 34.379916 180)
			(size 0.450088 0.450088)
			(layers "F.Cu" "F.Mask" "F.Paste")
			(net "ESPI_CPU0_R_D2")
		)
		(pad "DF26" smd circle
			(at -11.43 34.379916 180)
			(size 0.450088 0.450088)
			(layers "F.Cu" "F.Mask" "F.Paste")
			(net "GND")
		)
		(pad "DF27" smd circle
			(at -10.489946 34.379916 180)
			(size 0.450088 0.450088)
			(layers "F.Cu" "F.Mask" "F.Paste")
			(net "PD_ESPI_CPU0_CLK2")
		)
		(pad "DF28" smd circle
			(at -9.549892 34.379916 180)
			(size 0.450088 0.450088)
			(layers "F.Cu" "F.Mask" "F.Paste")
			(net "SPI_CPU0_R_D0")
		)
		(pad "DF29" smd circle
			(at -8.610092 34.379916 180)
			(size 0.450088 0.450088)
			(layers "F.Cu" "F.Mask" "F.Paste")
			(net "GND")
		)
		(pad "DF30" smd circle
			(at -7.670038 34.379916 180)
			(size 0.450088 0.450088)
			(layers "F.Cu" "F.Mask" "F.Paste")
			(net "SPI_CPU0_R_CS0_N")
		)
		(pad "DF31" smd circle
			(at -6.729984 34.379916 180)
			(size 0.450088 0.450088)
			(layers "F.Cu" "F.Mask" "F.Paste")
			(net "FM_BOARD_SKU_ID2")
		)
		(pad "DF32" smd circle
			(at -5.78993 34.379916 180)
			(size 0.450088 0.450088)
			(layers "F.Cu" "F.Mask" "F.Paste")
			(net "GND")
		)
		(pad "DF33" smd circle
			(at -4.849876 34.379916 180)
			(size 0.450088 0.450088)
			(layers "F.Cu" "F.Mask" "F.Paste")
			(net "FM_BOARD_SKU_ID0")
		)
		(pad "DF34" smd circle
			(at -3.910076 34.379916 180)
			(size 0.450088 0.450088)
			(layers "F.Cu" "F.Mask" "F.Paste")
			(net "TP_UART_CPU0_UART0_RTS_N")
		)
		(pad "DF35" smd circle
			(at -2.970022 34.379916 180)
			(size 0.450088 0.450088)
			(layers "F.Cu" "F.Mask" "F.Paste")
			(net "GND")
		)
		(pad "DF36" smd circle
			(at -2.029968 34.379916 180)
			(size 0.450088 0.450088)
			(layers "F.Cu" "F.Mask" "F.Paste")
			(net "FM_PASSWORD_CLEAR_R_N")
		)
		(pad "DF37" smd circle
			(at -1.089914 34.379916 180)
			(size 0.450088 0.450088)
			(layers "F.Cu" "F.Mask" "F.Paste")
			(net "GND")
		)
		(pad "DF39" smd circle
			(at 0.78994 34.379916 180)
			(size 0.450088 0.450088)
			(layers "F.Cu" "F.Mask" "F.Paste")
			(net "GND")
		)
		(pad "DF40" smd circle
			(at 1.729994 34.379916 180)
			(size 0.450088 0.450088)
			(layers "F.Cu" "F.Mask" "F.Paste")
			(net "FM_SMM_CRASHDUMP")
		)
		(pad "DF41" smd circle
			(at 2.670048 34.379916 180)
			(size 0.450088 0.450088)
			(layers "F.Cu" "F.Mask" "F.Paste")
			(net "Net_1948")
		)
		(pad "DF42" smd circle
			(at 3.610102 34.379916 180)
			(size 0.450088 0.450088)
			(layers "F.Cu" "F.Mask" "F.Paste")
			(net "GND")
		)
		(pad "DF43" smd circle
			(at 4.549902 34.379916 180)
			(size 0.450088 0.450088)
			(layers "F.Cu" "F.Mask" "F.Paste")
			(net "GND")
		)
		(pad "DF44" smd circle
			(at 5.489956 34.379916 180)
			(size 0.450088 0.450088)
			(layers "F.Cu" "F.Mask" "F.Paste")
			(net "GND")
		)
		(pad "DF45" smd circle
			(at 6.43001 34.379916 180)
			(size 0.450088 0.450088)
			(layers "F.Cu" "F.Mask" "F.Paste")
			(net "GND")
		)
		(pad "DF46" smd circle
			(at 7.370064 34.379916 180)
			(size 0.450088 0.450088)
			(layers "F.Cu" "F.Mask" "F.Paste")
			(net "GND")
		)
		(pad "DF47" smd circle
			(at 8.310118 34.379916 180)
			(size 0.450088 0.450088)
			(layers "F.Cu" "F.Mask" "F.Paste")
			(net "GND")
		)
		(pad "DF48" smd circle
			(at 9.249918 34.379916 180)
			(size 0.450088 0.450088)
			(layers "F.Cu" "F.Mask" "F.Paste")
			(net "GND")
		)
		(pad "DF49" smd circle
			(at 10.189972 34.379916 180)
			(size 0.450088 0.450088)
			(layers "F.Cu" "F.Mask" "F.Paste")
			(net "GND")
		)
		(pad "DF50" smd circle
			(at 11.130026 34.379916 180)
			(size 0.450088 0.450088)
			(layers "F.Cu" "F.Mask" "F.Paste")
			(net "GND")
		)
		(pad "DF51" smd circle
			(at 12.07008 34.379916 180)
			(size 0.450088 0.450088)
			(layers "F.Cu" "F.Mask" "F.Paste")
			(net "GND")
		)
		(pad "DF52" smd circle
			(at 13.00988 34.379916 180)
			(size 0.450088 0.450088)
			(layers "F.Cu" "F.Mask" "F.Paste")
			(net "GND")
		)
		(pad "DF53" smd circle
			(at 13.949934 34.379916 180)
			(size 0.450088 0.450088)
			(layers "F.Cu" "F.Mask" "F.Paste")
			(net "GND")
		)
		(pad "DF54" smd circle
			(at 14.889988 34.379916 180)
			(size 0.450088 0.450088)
			(layers "F.Cu" "F.Mask" "F.Paste")
			(net "GND")
		)
		(pad "DF55" smd circle
			(at 15.830042 34.379916 180)
			(size 0.450088 0.450088)
			(layers "F.Cu" "F.Mask" "F.Paste")
			(net "M_C_CPU0_SB_DQ<31>")
		)
		(pad "DF56" smd circle
			(at 16.770096 34.379916 180)
			(size 0.450088 0.450088)
			(layers "F.Cu" "F.Mask" "F.Paste")
			(net "GND")
		)
		(pad "DF57" smd circle
			(at 17.709896 34.379916 180)
			(size 0.450088 0.450088)
			(layers "F.Cu" "F.Mask" "F.Paste")
			(net "GND")
		)
		(pad "DF58" smd circle
			(at 18.64995 34.379916 180)
			(size 0.450088 0.450088)
			(layers "F.Cu" "F.Mask" "F.Paste")
			(net "GND")
		)
		(pad "DF59" smd circle
			(at 19.590004 34.379916 180)
			(size 0.450088 0.450088)
			(layers "F.Cu" "F.Mask" "F.Paste")
			(net "GND")
		)
		(pad "DF60" smd circle
			(at 20.530058 34.379916 180)
			(size 0.450088 0.450088)
			(layers "F.Cu" "F.Mask" "F.Paste")
			(net "M_D_CPU0_SB_DQ<31>")
		)
		(pad "DF61" smd circle
			(at 21.470112 34.379916 180)
			(size 0.450088 0.450088)
			(layers "F.Cu" "F.Mask" "F.Paste")
			(net "GND")
		)
		(pad "DF62" smd circle
			(at 22.409912 34.379916 180)
			(size 0.450088 0.450088)
			(layers "F.Cu" "F.Mask" "F.Paste")
			(net "M_B_CPU0_SB_DQ<31>")
		)
		(pad "DF63" smd circle
			(at 23.349966 34.379916 180)
			(size 0.450088 0.450088)
			(layers "F.Cu" "F.Mask" "F.Paste")
			(net "GND")
		)
		(pad "DF64" smd circle
			(at 24.29002 34.379916 180)
			(size 0.450088 0.450088)
			(layers "F.Cu" "F.Mask" "F.Paste")
			(net "GND")
		)
		(pad "DF65" smd circle
			(at 25.230074 34.379916 180)
			(size 0.450088 0.450088)
			(layers "F.Cu" "F.Mask" "F.Paste")
			(net "GND")
		)
		(pad "DF66" smd circle
			(at 26.170128 34.379916 180)
			(size 0.450088 0.450088)
			(layers "F.Cu" "F.Mask" "F.Paste")
			(net "GND")
		)
		(pad "DF67" smd circle
			(at 27.109928 34.379916 180)
			(size 0.450088 0.450088)
			(layers "F.Cu" "F.Mask" "F.Paste")
			(net "M_F_CPU0_SB_DQ<31>")
		)
		(pad "DF68" smd circle
			(at 28.049982 34.379916 180)
			(size 0.450088 0.450088)
			(layers "F.Cu" "F.Mask" "F.Paste")
			(net "GND")
		)
		(pad "DF69" smd circle
			(at 28.990036 34.379916 180)
			(size 0.450088 0.450088)
			(layers "F.Cu" "F.Mask" "F.Paste")
			(net "M_E_CPU0_SB_DQ<31>")
		)
		(pad "DF70" smd circle
			(at 29.93009 34.379916 180)
			(size 0.450088 0.450088)
			(layers "F.Cu" "F.Mask" "F.Paste")
			(net "GND")
		)
		(pad "DF71" smd circle
			(at 30.86989 34.379916 180)
			(size 0.450088 0.450088)
			(layers "F.Cu" "F.Mask" "F.Paste")
			(net "GND")
		)
		(pad "DF72" smd circle
			(at 31.809944 34.379916 180)
			(size 0.450088 0.450088)
			(layers "F.Cu" "F.Mask" "F.Paste")
			(net "GND")
		)
		(pad "DF73" smd circle
			(at 32.749998 34.379916 180)
			(size 0.450088 0.450088)
			(layers "F.Cu" "F.Mask" "F.Paste")
			(net "GND")
		)
		(pad "DF74" smd circle
			(at 33.690052 34.379916 180)
			(size 0.450088 0.450088)
			(layers "F.Cu" "F.Mask" "F.Paste")
			(net "M_A_CPU0_SB_DQ<31>")
		)
		(pad "DG1" smd circle
			(at -34.459926 35.189922 180)
			(size 0.450088 0.450088)
			(layers "F.Cu" "F.Mask" "F.Paste")
			(net "GND")
		)
		(pad "DG2" smd circle
			(at -33.519872 35.189922 180)
			(size 0.450088 0.450088)
			(layers "F.Cu" "F.Mask" "F.Paste")
			(net "GND")
		)
		(pad "DG3" smd circle
			(at -32.580072 35.189922 180)
			(size 0.450088 0.450088)
			(layers "F.Cu" "F.Mask" "F.Paste")
			(net "VSENSE_PVDDCR_CPU1_P0_DP")
		)
		(pad "DG4" smd circle
			(at -31.640018 35.189922 180)
			(size 0.450088 0.450088)
			(layers "F.Cu" "F.Mask" "F.Paste")
			(net "CPU0_SLP_S5_N")
		)
		(pad "DG5" smd circle
			(at -30.699964 35.189922 180)
			(size 0.450088 0.450088)
			(layers "F.Cu" "F.Mask" "F.Paste")
			(net "PVDD11_S3_P0")
		)
		(pad "DG6" smd circle
			(at -29.75991 35.189922 180)
			(size 0.450088 0.450088)
			(layers "F.Cu" "F.Mask" "F.Paste")
			(net "GND")
		)
		(pad "DG7" smd circle
			(at -28.82011 35.189922 180)
			(size 0.450088 0.450088)
			(layers "F.Cu" "F.Mask" "F.Paste")
			(net "GND")
		)
		(pad "DG8" smd circle
			(at -27.880056 35.189922 180)
			(size 0.450088 0.450088)
			(layers "F.Cu" "F.Mask" "F.Paste")
			(net "GND")
		)
		(pad "DG9" smd circle
			(at -26.940002 35.189922 180)
			(size 0.450088 0.450088)
			(layers "F.Cu" "F.Mask" "F.Paste")
			(net "GND")
		)
		(pad "DG10" smd circle
			(at -25.999948 35.189922 180)
			(size 0.450088 0.450088)
			(layers "F.Cu" "F.Mask" "F.Paste")
			(net "RST_CPU0_RSMRST_N")
		)
		(pad "DG11" smd circle
			(at -25.059894 35.189922 180)
			(size 0.450088 0.450088)
			(layers "F.Cu" "F.Mask" "F.Paste")
			(net "Net_1876")
		)
		(pad "DG12" smd circle
			(at -24.120094 35.189922 180)
			(size 0.450088 0.450088)
			(layers "F.Cu" "F.Mask" "F.Paste")
			(net "SMB_CPU0_4_R_SCL")
		)
		(pad "DG13" smd circle
			(at -23.18004 35.189922 180)
			(size 0.450088 0.450088)
			(layers "F.Cu" "F.Mask" "F.Paste")
			(net "GND")
		)
		(pad "DG14" smd circle
			(at -22.239986 35.189922 180)
			(size 0.450088 0.450088)
			(layers "F.Cu" "F.Mask" "F.Paste")
			(net "GND")
		)
		(pad "DG15" smd circle
			(at -21.299932 35.189922 180)
			(size 0.450088 0.450088)
			(layers "F.Cu" "F.Mask" "F.Paste")
			(net "GND")
		)
		(pad "DG16" smd circle
			(at -20.359878 35.189922 180)
			(size 0.450088 0.450088)
			(layers "F.Cu" "F.Mask" "F.Paste")
			(net "GND")
		)
		(pad "DG17" smd circle
			(at -19.420078 35.189922 180)
			(size 0.450088 0.450088)
			(layers "F.Cu" "F.Mask" "F.Paste")
			(net "Net_1940")
		)
		(pad "DG18" smd circle
			(at -18.480024 35.189922 180)
			(size 0.450088 0.450088)
			(layers "F.Cu" "F.Mask" "F.Paste")
			(net "GND")
		)
		(pad "DG19" smd circle
			(at -17.53997 35.189922 180)
			(size 0.450088 0.450088)
			(layers "F.Cu" "F.Mask" "F.Paste")
			(net "PVDDCR_CPU1_P0")
		)
		(pad "DG20" smd circle
			(at -16.599916 35.189922 180)
			(size 0.450088 0.450088)
			(layers "F.Cu" "F.Mask" "F.Paste")
			(net "GND")
		)
		(pad "DG21" smd circle
			(at -15.660116 35.189922 180)
			(size 0.450088 0.450088)
			(layers "F.Cu" "F.Mask" "F.Paste")
			(net "GND")
		)
		(pad "DG22" smd circle
			(at -14.720062 35.189922 180)
			(size 0.450088 0.450088)
			(layers "F.Cu" "F.Mask" "F.Paste")
			(net "SPI_CPU0_R_D1")
		)
		(pad "DG23" smd circle
			(at -13.780008 35.189922 180)
			(size 0.450088 0.450088)
			(layers "F.Cu" "F.Mask" "F.Paste")
			(net "CLK_ESPI_CPU0_R_CLK1")
		)
		(pad "DG24" smd circle
			(at -12.839954 35.189922 180)
			(size 0.450088 0.450088)
			(layers "F.Cu" "F.Mask" "F.Paste")
			(net "GND")
		)
		(pad "DG25" smd circle
			(at -11.8999 35.189922 180)
			(size 0.450088 0.450088)
			(layers "F.Cu" "F.Mask" "F.Paste")
			(net "ESPI_CPU0_R_D3")
		)
		(pad "DG26" smd circle
			(at -10.9601 35.189922 180)
			(size 0.450088 0.450088)
			(layers "F.Cu" "F.Mask" "F.Paste")
			(net "SPI_CPU0_R_CS1_N")
		)
		(pad "DG27" smd circle
			(at -10.020046 35.189922 180)
			(size 0.450088 0.450088)
			(layers "F.Cu" "F.Mask" "F.Paste")
			(net "GND")
		)
		(pad "DG28" smd circle
			(at -9.079992 35.189922 180)
			(size 0.450088 0.450088)
			(layers "F.Cu" "F.Mask" "F.Paste")
			(net "CPU0_ESPI_CS0_N")
		)
		(pad "DG29" smd circle
			(at -8.139938 35.189922 180)
			(size 0.450088 0.450088)
			(layers "F.Cu" "F.Mask" "F.Paste")
			(net "SPI_CPU0_R_D3")
		)
		(pad "DG30" smd circle
			(at -7.199884 35.189922 180)
			(size 0.450088 0.450088)
			(layers "F.Cu" "F.Mask" "F.Paste")
			(net "GND")
		)
		(pad "DG31" smd circle
			(at -6.260084 35.189922 180)
			(size 0.450088 0.450088)
			(layers "F.Cu" "F.Mask" "F.Paste")
			(net "FM_BOARD_SKU_ID3")
		)
	)
)
